# SCM (Grand Teton) — schematic netlist excerpt (pin names and nets, part order shuffled) for the footprints in the layout excerpt that follows; sources: Cadence DE-HDL packaged netlist, KiCad conversion of 12092022_DA0F0TMDCD0_F0T_Management_Board_D_brd_V3_OCP.brd

R487  Q_RES  4.7K 1% EMPTY  pkg 0402LF  page 45 : A = SPI_PCH_CS0_FLASH_R1_N ; B = GND
R863  Q_RES  22 1% CHIP  pkg 0402LF  page 44 : A = SPI_SYS_HOLD_R_IO3 ; B = SPI_SYS_MUX_HOLD_IO3

(kicad_pcb
	(version 20260206)
	(generator "pcbnew")
	(generator_version "10.0")
	(general
		(thickness 1.6)
		(legacy_teardrops no)
	)
	(paper "A4")
	(title_block
		(title "12092022_DA0F0TMDCD0_F0T_Management_Board_D_brd_V3_OCP.brd")
		(comment 1 "Grand Teton / footprints 699-700 of 1440")
	)
	(layers
		(0 "F.Cu" signal "TOP")
		(4 "In1.Cu" signal "GND")
		(6 "In2.Cu" signal "IN1")
		(8 "In3.Cu" signal "GND1")
		(10 "In4.Cu" signal "IN2")
		(12 "In5.Cu" signal "VCC")
		(14 "In6.Cu" signal "VCC1")
		(16 "In7.Cu" signal "IN3")
		(18 "In8.Cu" signal "GND2")
		(20 "In9.Cu" signal "IN4")
		(22 "In10.Cu" signal "GND3")
		(2 "B.Cu" signal "BOTTOM")
		(9 "F.Adhes" user "F.Adhesive")
		(11 "B.Adhes" user "B.Adhesive")
		(13 "F.Paste" user "Package Geometry/Pastemask Top")
		(15 "B.Paste" user "Package Geometry/Pastemask Bottom")
		(5 "F.SilkS" user "Ref Des/Silkscreen Top")
		(7 "B.SilkS" user "Ref Des/Silkscreen Bottom")
		(1 "F.Mask" user "Board Geometry/Soldermask Top")
		(3 "B.Mask" user "Board Geometry/Soldermask Bottom")
		(17 "Dwgs.User" user "User.Drawings")
		(19 "Cmts.User" user "User.Comments")
		(21 "Eco1.User" user "User.Eco1")
		(23 "Eco2.User" user "User.Eco2")
		(25 "Edge.Cuts" user "Board Geometry/Outline")
		(27 "Margin" user)
		(31 "F.CrtYd" user "Package Geometry/Place Bound Top")
		(29 "B.CrtYd" user "Package Geometry/Place Bound Bottom")
		(35 "F.Fab" user "Ref Des/Assembly Top")
		(33 "B.Fab" user "Ref Des/Assembly Bottom")
	)
	(footprint ""
		(layer "F.Cu")
		(at 52.6542 -109.3978 -90)
		(property "Reference" "R863"
			(at 0 0 270)
			(layer "F.SilkS")
			(hide yes)
			(effects
				(font
					(size 1.27 1.27)
				)
			)
		)
		(property "Value" ""
			(at 0 0 270)
			(layer "F.Fab")
			(effects
				(font
					(size 1.27 1.27)
				)
			)
		)
		(duplicate_pad_numbers_are_jumpers no)
		(fp_line
			(start -0.7874 0.4064)
			(end -0.7874 -0.4064)
			(stroke
				(width 0.1524)
				(type default)
			)
			(layer "F.SilkS")
		)
		(fp_line
			(start 0.7874 0.4064)
			(end -0.7874 0.4064)
			(stroke
				(width 0.1524)
				(type default)
			)
			(layer "F.SilkS")
		)
		(fp_line
			(start -0.7874 -0.4064)
			(end 0.7874 -0.4064)
			(stroke
				(width 0.1524)
				(type default)
			)
			(layer "F.SilkS")
		)
		(fp_line
			(start 0.7874 -0.4064)
			(end 0.7874 0.4064)
			(stroke
				(width 0.1524)
				(type default)
			)
			(layer "F.SilkS")
		)
		(fp_line
			(start -0.67945 0.3048)
			(end -0.67945 -0.305054)
			(stroke
				(width 0.1)
				(type default)
			)
			(layer "F.Fab")
		)
		(fp_line
			(start -0.12065 0.3048)
			(end -0.67945 0.3048)
			(stroke
				(width 0.1)
				(type default)
			)
			(layer "F.Fab")
		)
		(fp_line
			(start 0.120396 0.3048)
			(end 0.120396 0.2794)
			(stroke
				(width 0.1)
				(type default)
			)
			(layer "F.Fab")
		)
		(fp_line
			(start 0.67945 0.3048)
			(end 0.120396 0.3048)
			(stroke
				(width 0.1)
				(type default)
			)
			(layer "F.Fab")
		)
		(fp_line
			(start -0.12065 0.2794)
			(end -0.12065 0.3048)
			(stroke
				(width 0.1)
				(type default)
			)
			(layer "F.Fab")
		)
		(fp_line
			(start 0.120396 0.2794)
			(end -0.12065 0.2794)
			(stroke
				(width 0.1)
				(type default)
			)
			(layer "F.Fab")
		)
		(fp_line
			(start -0.12065 -0.2794)
			(end 0.12065 -0.2794)
			(stroke
				(width 0.1)
				(type default)
			)
			(layer "F.Fab")
		)
		(fp_line
			(start 0.12065 -0.2794)
			(end 0.12065 -0.3048)
			(stroke
				(width 0.1)
				(type default)
			)
			(layer "F.Fab")
		)
		(fp_line
			(start 0.12065 -0.3048)
			(end 0.67945 -0.3048)
			(stroke
				(width 0.1)
				(type default)
			)
			(layer "F.Fab")
		)
		(fp_line
			(start 0.67945 -0.3048)
			(end 0.67945 0.3048)
			(stroke
				(width 0.1)
				(type default)
			)
			(layer "F.Fab")
		)
		(fp_line
			(start -0.67945 -0.305054)
			(end -0.12065 -0.305054)
			(stroke
				(width 0.1)
				(type default)
			)
			(layer "F.Fab")
		)
		(fp_line
			(start -0.12065 -0.305054)
			(end -0.12065 -0.2794)
			(stroke
				(width 0.1)
				(type default)
			)
			(layer "F.Fab")
		)
		(pad "1" smd circle
			(at -0.40005 0 270)
			(size 0 0)
			(layers "F.Cu" "F.Mask" "F.Paste")
			(net "SPI_SYS_HOLD_R_IO3")
		)
		(pad "2" smd circle
			(at 0.40005 0 270)
			(size 0 0)
			(layers "F.Cu" "F.Mask" "F.Paste")
			(net "SPI_SYS_MUX_HOLD_IO3")
		)
	)
	(footprint ""
		(layer "F.Cu")
		(at 41.916604 -87.679784 -90)
		(property "Reference" "R487"
			(at 0 0 270)
			(layer "F.SilkS")
			(hide yes)
			(effects
				(font
					(size 1.27 1.27)
				)
			)
		)
		(property "Value" ""
			(at 0 0 270)
			(layer "F.Fab")
			(effects
				(font
					(size 1.27 1.27)
				)
			)
		)
		(duplicate_pad_numbers_are_jumpers no)
		(fp_line
			(start -0.7874 0.4064)
			(end -0.7874 -0.4064)
			(stroke
				(width 0.1524)
				(type default)
			)
			(layer "F.SilkS")
		)
		(fp_line
			(start 0.7874 0.4064)
			(end -0.7874 0.4064)
			(stroke
				(width 0.1524)
				(type default)
			)
			(layer "F.SilkS")
		)
		(fp_line
			(start -0.7874 -0.4064)
			(end 0.7874 -0.4064)
			(stroke
				(width 0.1524)
				(type default)
			)
			(layer "F.SilkS")
		)
		(fp_line
			(start 0.7874 -0.4064)
			(end 0.7874 0.4064)
			(stroke
				(width 0.1524)
				(type default)
			)
			(layer "F.SilkS")
		)
		(fp_line
			(start -0.67945 0.3048)
			(end -0.67945 -0.305054)
			(stroke
				(width 0.1)
				(type default)
			)
			(layer "F.Fab")
		)
		(fp_line
			(start -0.12065 0.3048)
			(end -0.67945 0.3048)
			(stroke
				(width 0.1)
				(type default)
			)
			(layer "F.Fab")
		)
		(fp_line
			(start 0.120396 0.3048)
			(end 0.120396 0.2794)
			(stroke
				(width 0.1)
				(type default)
			)
			(layer "F.Fab")
		)
		(fp_line
			(start 0.67945 0.3048)
			(end 0.120396 0.3048)
			(stroke
				(width 0.1)
				(type default)
			)
			(layer "F.Fab")
		)
		(fp_line
			(start -0.12065 0.2794)
			(end -0.12065 0.3048)
			(stroke
				(width 0.1)
				(type default)
			)
			(layer "F.Fab")
		)
		(fp_line
			(start 0.120396 0.2794)
			(end -0.12065 0.2794)
			(stroke
				(width 0.1)
				(type default)
			)
			(layer "F.Fab")
		)
		(fp_line
			(start -0.12065 -0.2794)
			(end 0.12065 -0.2794)
			(stroke
				(width 0.1)
				(type default)
			)
			(layer "F.Fab")
		)
		(fp_line
			(start 0.12065 -0.2794)
			(end 0.12065 -0.3048)
			(stroke
				(width 0.1)
				(type default)
			)
			(layer "F.Fab")
		)
		(fp_line
			(start 0.12065 -0.3048)
			(end 0.67945 -0.3048)
			(stroke
				(width 0.1)
				(type default)
			)
			(layer "F.Fab")
		)
		(fp_line
			(start 0.67945 -0.3048)
			(end 0.67945 0.3048)
			(stroke
				(width 0.1)
				(type default)
			)
			(layer "F.Fab")
		)
		(fp_line
			(start -0.67945 -0.305054)
			(end -0.12065 -0.305054)
			(stroke
				(width 0.1)
				(type default)
			)
			(layer "F.Fab")
		)
		(fp_line
			(start -0.12065 -0.305054)
			(end -0.12065 -0.2794)
			(stroke
				(width 0.1)
				(type default)
			)
			(layer "F.Fab")
		)
		(pad "1" smd circle
			(at -0.40005 0 270)
			(size 0 0)
			(layers "F.Cu" "F.Mask" "F.Paste")
			(net "SPI_PCH_CS0_FLASH_R1_N")
		)
		(pad "2" smd circle
			(at 0.40005 0 270)
			(size 0 0)
			(layers "F.Cu" "F.Mask" "F.Paste")
			(net "GND")
		)
	)
)
